(kicad_pcb
	(version 20260206)
	(generator "pcbnew")
	(generator_version "10.0")
	(general
		(thickness 1.6)
		(legacy_teardrops no)
	)
	(paper "A4")
	(title_block
		(title "v1-chassis-manager — T6M_CM_d_v01_1031_1645.brd")
		(comment 1 "Open CloudServer (Microsoft) / footprint 1045 of 2512 (J2), pads 120-208 of 208")
	)
	(layers
		(0 "F.Cu" signal "TOP")
		(4 "In1.Cu" signal "GND1")
		(6 "In2.Cu" signal "IN1")
		(8 "In3.Cu" signal "VCC1")
		(10 "In4.Cu" signal "VCC2")
		(12 "In5.Cu" signal "GND2")
		(14 "In6.Cu" signal "IN2")
		(16 "In7.Cu" signal "IN3")
		(18 "In8.Cu" signal "GND3")
		(2 "B.Cu" signal "BOTTOM")
		(9 "F.Adhes" user "F.Adhesive")
		(11 "B.Adhes" user "B.Adhesive")
		(13 "F.Paste" user "Package Geometry/Pastemask Top")
		(15 "B.Paste" user "Package Geometry/Pastemask Bottom")
		(5 "F.SilkS" user "Ref Des/Silkscreen Top")
		(7 "B.SilkS" user "Ref Des/Silkscreen Bottom")
		(1 "F.Mask" user "Board Geometry/Soldermask Top")
		(3 "B.Mask" user "Board Geometry/Soldermask Bottom")
		(17 "Dwgs.User" user "User.Drawings")
		(19 "Cmts.User" user "User.Comments")
		(21 "Eco1.User" user "User.Eco1")
		(23 "Eco2.User" user "User.Eco2")
		(25 "Edge.Cuts" user "Board Geometry/Outline")
		(27 "Margin" user)
		(31 "F.CrtYd" user "Package Geometry/Place Bound Top")
		(29 "B.CrtYd" user "Package Geometry/Place Bound Bottom")
		(35 "F.Fab" user "Ref Des/Assembly Top")
		(33 "B.Fab" user "Ref Des/Assembly Bottom")
	)
	(footprint ""
		(layer "F.Cu")
		(at 40.350186 -20.94992 90)
		(property "Reference" "J2"
			(at -2.420874 10.237724 0)
			(unlocked yes)
			(layer "F.SilkS")
			(effects
				(font
					(size 0.7874 0.5842)
					(thickness 0.1524)
				)
				(justify left)
			)
		)
		(property "Value" ""
			(at 0 0 90)
			(layer "F.Fab")
			(effects
				(font
					(size 1.27 1.27)
				)
			)
		)
		(duplicate_pad_numbers_are_jumpers no)
		(pad "118" smd rect
			(at 8.199882 37.500052)
			(size 0.381 2.0574)
			(layers "F.Cu" "F.Mask" "F.Paste")
			(net "TP_DDR3_NODE1_CS3_L")
		)
		(pad "119" smd rect
			(at 0 37.800026)
			(size 0.381 2.0574)
			(layers "F.Cu" "F.Mask" "F.Paste")
			(net "M_DDR3_NODE1_BS0")
		)
		(pad "120" smd rect
			(at 8.199882 38.1)
			(size 0.381 2.0574)
			(layers "F.Cu" "F.Mask" "F.Paste")
			(net "TP_DDR3_NODE1_CS2_L")
		)
		(pad "121" smd rect
			(at 0 38.399974)
			(size 0.381 2.0574)
			(layers "F.Cu" "F.Mask" "F.Paste")
			(net "M_DDR3_NODE1_WE_L")
		)
		(pad "122" smd rect
			(at 8.199882 38.699948)
			(size 0.381 2.0574)
			(layers "F.Cu" "F.Mask" "F.Paste")
			(net "M_DDR3_NODE1_RAS_L")
		)
		(pad "123" smd rect
			(at 0 38.999922)
			(size 0.381 2.0574)
			(layers "F.Cu" "F.Mask" "F.Paste")
			(net "PV_VDDR_NODE1")
		)
		(pad "124" smd rect
			(at 8.199882 39.299896)
			(size 0.381 2.0574)
			(layers "F.Cu" "F.Mask" "F.Paste")
			(net "PV_VDDR_NODE1")
		)
		(pad "125" smd rect
			(at 0 39.600124)
			(size 0.381 2.0574)
			(layers "F.Cu" "F.Mask" "F.Paste")
			(net "M_DDR3_NODE1_CAS_L")
		)
		(pad "126" smd rect
			(at 8.199882 39.900098)
			(size 0.381 2.0574)
			(layers "F.Cu" "F.Mask" "F.Paste")
			(net "M_DDR3_NODE1_ODT0")
		)
		(pad "127" smd rect
			(at 0 40.200072)
			(size 0.381 2.0574)
			(layers "F.Cu" "F.Mask" "F.Paste")
			(net "M_DDR3_NODE1_CS0_L")
		)
		(pad "128" smd rect
			(at 8.199882 40.500046)
			(size 0.381 2.0574)
			(layers "F.Cu" "F.Mask" "F.Paste")
			(net "M_DDR3_NODE1_ODT1")
		)
		(pad "129" smd rect
			(at 0 40.80002)
			(size 0.381 2.0574)
			(layers "F.Cu" "F.Mask" "F.Paste")
			(net "M_DDR3_NODE1_CS1_L")
		)
		(pad "130" smd rect
			(at 8.199882 41.099994)
			(size 0.381 2.0574)
			(layers "F.Cu" "F.Mask" "F.Paste")
			(net "M_DDR3_NODE1_MA13")
		)
		(pad "131" smd rect
			(at 0 41.399968)
			(size 0.381 2.0574)
			(layers "F.Cu" "F.Mask" "F.Paste")
			(net "PV_VDDR_NODE1")
		)
		(pad "132" smd rect
			(at 8.199882 41.699942)
			(size 0.381 2.0574)
			(layers "F.Cu" "F.Mask" "F.Paste")
			(net "PV_VDDR_NODE1")
		)
		(pad "133" smd rect
			(at 0 41.999916)
			(size 0.381 2.0574)
			(layers "F.Cu" "F.Mask" "F.Paste")
			(net "M1_DQ_NODE1_DQ32")
		)
		(pad "134" smd rect
			(at 8.199882 42.29989)
			(size 0.381 2.0574)
			(layers "F.Cu" "F.Mask" "F.Paste")
			(net "M1_DQ_NODE1_DQ36")
		)
		(pad "135" smd rect
			(at 0 42.600118)
			(size 0.381 2.0574)
			(layers "F.Cu" "F.Mask" "F.Paste")
			(net "M1_DQ_NODE1_DQ33")
		)
		(pad "136" smd rect
			(at 8.199882 42.900092)
			(size 0.381 2.0574)
			(layers "F.Cu" "F.Mask" "F.Paste")
			(net "M1_DQ_NODE1_DQ37")
		)
		(pad "137" smd rect
			(at 0 43.200066)
			(size 0.381 2.0574)
			(layers "F.Cu" "F.Mask" "F.Paste")
			(net "GND")
		)
		(pad "138" smd rect
			(at 8.199882 43.50004)
			(size 0.381 2.0574)
			(layers "F.Cu" "F.Mask" "F.Paste")
			(net "GND")
		)
		(pad "139" smd rect
			(at 0 43.800014)
			(size 0.381 2.0574)
			(layers "F.Cu" "F.Mask" "F.Paste")
			(net "M_DDR3_NODE1_DQS4N")
		)
		(pad "140" smd rect
			(at 8.199882 44.099988)
			(size 0.381 2.0574)
			(layers "F.Cu" "F.Mask" "F.Paste")
			(net "PD_NODE1_DM4")
		)
		(pad "141" smd rect
			(at 0 44.399962)
			(size 0.381 2.0574)
			(layers "F.Cu" "F.Mask" "F.Paste")
			(net "M_DDR3_NODE1_DQS4P")
		)
		(pad "142" smd rect
			(at 8.199882 44.699936)
			(size 0.381 2.0574)
			(layers "F.Cu" "F.Mask" "F.Paste")
			(net "M1_DQ_NODE1_DQ38")
		)
		(pad "143" smd rect
			(at 0 44.99991)
			(size 0.381 2.0574)
			(layers "F.Cu" "F.Mask" "F.Paste")
			(net "GND")
		)
		(pad "144" smd rect
			(at 8.199882 45.299884)
			(size 0.381 2.0574)
			(layers "F.Cu" "F.Mask" "F.Paste")
			(net "M1_DQ_NODE1_DQ39")
		)
		(pad "145" smd rect
			(at 0 45.600112)
			(size 0.381 2.0574)
			(layers "F.Cu" "F.Mask" "F.Paste")
			(net "M1_DQ_NODE1_DQ34")
		)
		(pad "146" smd rect
			(at 8.199882 45.900086)
			(size 0.381 2.0574)
			(layers "F.Cu" "F.Mask" "F.Paste")
			(net "GND")
		)
		(pad "147" smd rect
			(at 0 46.20006)
			(size 0.381 2.0574)
			(layers "F.Cu" "F.Mask" "F.Paste")
			(net "M1_DQ_NODE1_DQ35")
		)
		(pad "148" smd rect
			(at 8.199882 46.500034)
			(size 0.381 2.0574)
			(layers "F.Cu" "F.Mask" "F.Paste")
			(net "M1_DQ_NODE1_DQ44")
		)
		(pad "149" smd rect
			(at 0 46.800008)
			(size 0.381 2.0574)
			(layers "F.Cu" "F.Mask" "F.Paste")
			(net "GND")
		)
		(pad "150" smd rect
			(at 8.199882 47.099982)
			(size 0.381 2.0574)
			(layers "F.Cu" "F.Mask" "F.Paste")
			(net "M1_DQ_NODE1_DQ45")
		)
		(pad "151" smd rect
			(at 0 47.399956)
			(size 0.381 2.0574)
			(layers "F.Cu" "F.Mask" "F.Paste")
			(net "M1_DQ_NODE1_DQ40")
		)
		(pad "152" smd rect
			(at 8.199882 47.69993)
			(size 0.381 2.0574)
			(layers "F.Cu" "F.Mask" "F.Paste")
			(net "GND")
		)
		(pad "153" smd rect
			(at 0 47.999904)
			(size 0.381 2.0574)
			(layers "F.Cu" "F.Mask" "F.Paste")
			(net "M1_DQ_NODE1_DQ41")
		)
		(pad "154" smd rect
			(at 8.199882 48.299878)
			(size 0.381 2.0574)
			(layers "F.Cu" "F.Mask" "F.Paste")
			(net "M_DDR3_NODE1_DQS5N")
		)
		(pad "155" smd rect
			(at 0 48.600106)
			(size 0.381 2.0574)
			(layers "F.Cu" "F.Mask" "F.Paste")
			(net "GND")
		)
		(pad "156" smd rect
			(at 8.199882 48.90008)
			(size 0.381 2.0574)
			(layers "F.Cu" "F.Mask" "F.Paste")
			(net "M_DDR3_NODE1_DQS5P")
		)
		(pad "157" smd rect
			(at 0 49.200054)
			(size 0.381 2.0574)
			(layers "F.Cu" "F.Mask" "F.Paste")
			(net "PD_NODE1_DM5")
		)
		(pad "158" smd rect
			(at 8.199882 49.500028)
			(size 0.381 2.0574)
			(layers "F.Cu" "F.Mask" "F.Paste")
			(net "GND")
		)
		(pad "159" smd rect
			(at 0 49.800002)
			(size 0.381 2.0574)
			(layers "F.Cu" "F.Mask" "F.Paste")
			(net "M1_DQ_NODE1_DQ42")
		)
		(pad "160" smd rect
			(at 8.199882 50.099976)
			(size 0.381 2.0574)
			(layers "F.Cu" "F.Mask" "F.Paste")
			(net "M1_DQ_NODE1_DQ46")
		)
		(pad "161" smd rect
			(at 0 50.39995)
			(size 0.381 2.0574)
			(layers "F.Cu" "F.Mask" "F.Paste")
			(net "M1_DQ_NODE1_DQ43")
		)
		(pad "162" smd rect
			(at 8.199882 50.699924)
			(size 0.381 2.0574)
			(layers "F.Cu" "F.Mask" "F.Paste")
			(net "M1_DQ_NODE1_DQ47")
		)
		(pad "163" smd rect
			(at 0 50.999898)
			(size 0.381 2.0574)
			(layers "F.Cu" "F.Mask" "F.Paste")
			(net "GND")
		)
		(pad "164" smd rect
			(at 8.199882 51.299872)
			(size 0.381 2.0574)
			(layers "F.Cu" "F.Mask" "F.Paste")
			(net "GND")
		)
		(pad "165" smd rect
			(at 0 51.6001)
			(size 0.381 2.0574)
			(layers "F.Cu" "F.Mask" "F.Paste")
			(net "M1_DQ_NODE1_DQ48")
		)
		(pad "166" smd rect
			(at 8.199882 51.900074)
			(size 0.381 2.0574)
			(layers "F.Cu" "F.Mask" "F.Paste")
			(net "M1_DQ_NODE1_DQ52")
		)
		(pad "167" smd rect
			(at 0 52.200048)
			(size 0.381 2.0574)
			(layers "F.Cu" "F.Mask" "F.Paste")
			(net "M1_DQ_NODE1_DQ49")
		)
		(pad "168" smd rect
			(at 8.199882 52.500022)
			(size 0.381 2.0574)
			(layers "F.Cu" "F.Mask" "F.Paste")
			(net "M1_DQ_NODE1_DQ53")
		)
		(pad "169" smd rect
			(at 0 52.799996)
			(size 0.381 2.0574)
			(layers "F.Cu" "F.Mask" "F.Paste")
			(net "GND")
		)
		(pad "170" smd rect
			(at 8.199882 53.09997)
			(size 0.381 2.0574)
			(layers "F.Cu" "F.Mask" "F.Paste")
			(net "GND")
		)
		(pad "171" smd rect
			(at 0 53.399944)
			(size 0.381 2.0574)
			(layers "F.Cu" "F.Mask" "F.Paste")
			(net "M_DDR3_NODE1_DQS6N")
		)
		(pad "172" smd rect
			(at 8.199882 53.699918)
			(size 0.381 2.0574)
			(layers "F.Cu" "F.Mask" "F.Paste")
			(net "PD_NODE1_DM6")
		)
		(pad "173" smd rect
			(at 0 53.999892)
			(size 0.381 2.0574)
			(layers "F.Cu" "F.Mask" "F.Paste")
			(net "M_DDR3_NODE1_DQS6P")
		)
		(pad "174" smd rect
			(at 8.199882 54.30012)
			(size 0.381 2.0574)
			(layers "F.Cu" "F.Mask" "F.Paste")
			(net "M1_DQ_NODE1_DQ54")
		)
		(pad "175" smd rect
			(at 0 54.600094)
			(size 0.381 2.0574)
			(layers "F.Cu" "F.Mask" "F.Paste")
			(net "GND")
		)
		(pad "176" smd rect
			(at 8.199882 54.900068)
			(size 0.381 2.0574)
			(layers "F.Cu" "F.Mask" "F.Paste")
			(net "M1_DQ_NODE1_DQ55")
		)
		(pad "177" smd rect
			(at 0 55.200042)
			(size 0.381 2.0574)
			(layers "F.Cu" "F.Mask" "F.Paste")
			(net "M1_DQ_NODE1_DQ50")
		)
		(pad "178" smd rect
			(at 8.199882 55.500016)
			(size 0.381 2.0574)
			(layers "F.Cu" "F.Mask" "F.Paste")
			(net "GND")
		)
		(pad "179" smd rect
			(at 0 55.79999)
			(size 0.381 2.0574)
			(layers "F.Cu" "F.Mask" "F.Paste")
			(net "M1_DQ_NODE1_DQ51")
		)
		(pad "180" smd rect
			(at 8.199882 56.099964)
			(size 0.381 2.0574)
			(layers "F.Cu" "F.Mask" "F.Paste")
			(net "M1_DQ_NODE1_DQ60")
		)
		(pad "181" smd rect
			(at 0 56.399938)
			(size 0.381 2.0574)
			(layers "F.Cu" "F.Mask" "F.Paste")
			(net "GND")
		)
		(pad "182" smd rect
			(at 8.199882 56.699912)
			(size 0.381 2.0574)
			(layers "F.Cu" "F.Mask" "F.Paste")
			(net "M1_DQ_NODE1_DQ61")
		)
		(pad "183" smd rect
			(at 0 56.999886)
			(size 0.381 2.0574)
			(layers "F.Cu" "F.Mask" "F.Paste")
			(net "M1_DQ_NODE1_DQ56")
		)
		(pad "184" smd rect
			(at 8.199882 57.300114)
			(size 0.381 2.0574)
			(layers "F.Cu" "F.Mask" "F.Paste")
			(net "GND")
		)
		(pad "185" smd rect
			(at 0 57.600088)
			(size 0.381 2.0574)
			(layers "F.Cu" "F.Mask" "F.Paste")
			(net "M1_DQ_NODE1_DQ57")
		)
		(pad "186" smd rect
			(at 8.199882 57.900062)
			(size 0.381 2.0574)
			(layers "F.Cu" "F.Mask" "F.Paste")
			(net "M_DDR3_NODE1_DQS7N")
		)
		(pad "187" smd rect
			(at 0 58.200036)
			(size 0.381 2.0574)
			(layers "F.Cu" "F.Mask" "F.Paste")
			(net "GND")
		)
		(pad "188" smd rect
			(at 8.199882 58.50001)
			(size 0.381 2.0574)
			(layers "F.Cu" "F.Mask" "F.Paste")
			(net "M_DDR3_NODE1_DQS7P")
		)
		(pad "189" smd rect
			(at 0 58.799984)
			(size 0.381 2.0574)
			(layers "F.Cu" "F.Mask" "F.Paste")
			(net "PD_NODE1_DM7")
		)
		(pad "190" smd rect
			(at 8.199882 59.099958)
			(size 0.381 2.0574)
			(layers "F.Cu" "F.Mask" "F.Paste")
			(net "GND")
		)
		(pad "191" smd rect
			(at 0 59.399932)
			(size 0.381 2.0574)
			(layers "F.Cu" "F.Mask" "F.Paste")
			(net "M1_DQ_NODE1_DQ58")
		)
		(pad "192" smd rect
			(at 8.199882 59.699906)
			(size 0.381 2.0574)
			(layers "F.Cu" "F.Mask" "F.Paste")
			(net "M1_DQ_NODE1_DQ62")
		)
		(pad "193" smd rect
			(at 0 59.99988)
			(size 0.381 2.0574)
			(layers "F.Cu" "F.Mask" "F.Paste")
			(net "M1_DQ_NODE1_DQ59")
		)
		(pad "194" smd rect
			(at 8.199882 60.300108)
			(size 0.381 2.0574)
			(layers "F.Cu" "F.Mask" "F.Paste")
			(net "M1_DQ_NODE1_DQ63")
		)
		(pad "195" smd rect
			(at 0 60.600082)
			(size 0.381 2.0574)
			(layers "F.Cu" "F.Mask" "F.Paste")
			(net "GND")
		)
		(pad "196" smd rect
			(at 8.199882 60.900056)
			(size 0.381 2.0574)
			(layers "F.Cu" "F.Mask" "F.Paste")
			(net "GND")
		)
		(pad "197" smd rect
			(at 0 61.20003)
			(size 0.381 2.0574)
			(layers "F.Cu" "F.Mask" "F.Paste")
			(net "GND")
		)
		(pad "198" smd rect
			(at 8.199882 61.500004)
			(size 0.381 2.0574)
			(layers "F.Cu" "F.Mask" "F.Paste")
			(net "TP_NODE1_ERR_OUT_DIMM0")
		)
		(pad "199" smd rect
			(at 0 61.799978)
			(size 0.381 2.0574)
			(layers "F.Cu" "F.Mask" "F.Paste")
			(net "P3V3_NODE1")
		)
		(pad "200" smd rect
			(at 8.199882 62.099952)
			(size 0.381 2.0574)
			(layers "F.Cu" "F.Mask" "F.Paste")
			(net "SMB_DIMM_NODE1_DAT")
		)
		(pad "201" smd rect
			(at 0 62.399926)
			(size 0.381 2.0574)
			(layers "F.Cu" "F.Mask" "F.Paste")
			(net "GND")
		)
		(pad "202" smd rect
			(at 8.199882 62.6999)
			(size 0.381 2.0574)
			(layers "F.Cu" "F.Mask" "F.Paste")
			(net "SMB_DIMM_NODE1_CLK")
		)
		(pad "203" smd rect
			(at 0 63.000128)
			(size 0.381 2.0574)
			(layers "F.Cu" "F.Mask" "F.Paste")
			(net "PV_VTT_DDR_NODE1")
		)
		(pad "204" smd rect
			(at 8.199882 63.300102)
			(size 0.381 2.0574)
			(layers "F.Cu" "F.Mask" "F.Paste")
			(net "PV_VTT_DDR_NODE1")
		)
		(pad "G1" smd rect
			(at 16.100044 -5.80009)
			(size 4.6228 4.699)
			(layers "F.Cu" "F.Mask" "F.Paste")
			(net "GND")
		)
		(pad "G2" smd rect
			(at 16.100044 69.099938)
			(size 4.6228 4.699)
			(layers "F.Cu" "F.Mask" "F.Paste")
			(net "GND")
		)
	)
)
